# S9S_MB_2U (Grand Teton) — schematic netlist excerpt (pin names and nets, part order shuffled) for the footprints in the layout excerpt that follows; sources: Cadence DE-HDL packaged netlist, KiCad conversion of 03242023_DA0F0TMBIJ0_F0T_Motherboard_J_brd_V01_OCP.brd

PC16  Q_CAPP  560UF 2.5V 20% OSCON  pkg THLF  page 267 : A = PVCCIN_CPU0 ; B = GND
JP4003_12  TP  NA  pkg TP_BOM ONLY  page 312 : TP = NC
R4391  Q_RES  150 1% CHIP  pkg 0402LF  page 225 : A = PD_GTL2014_ERROR_B0 ; B = GND
R3396  Q_RES  2.2K 5% CHIP  pkg 0402LF  page 231 : A = P3V3_AUX ; B = SMB_INA230_3V3AUX_SDA

(kicad_pcb
	(version 20260206)
	(generator "pcbnew")
	(generator_version "10.0")
	(general
		(thickness 1.6)
		(legacy_teardrops no)
	)
	(paper "A4")
	(title_block
		(title "03242023_DA0F0TMBIJ0_F0T_Motherboard_J_brd_V01_OCP.brd")
		(comment 1 "Grand Teton / footprints 545-548 of 6105")
	)
	(layers
		(0 "F.Cu" signal "TOP")
		(4 "In1.Cu" signal "GND")
		(6 "In2.Cu" signal "IN1")
		(8 "In3.Cu" signal "GND1")
		(10 "In4.Cu" signal "IN2")
		(12 "In5.Cu" signal "GND2")
		(14 "In6.Cu" signal "IN3")
		(16 "In7.Cu" signal "GND3")
		(18 "In8.Cu" signal "VCC")
		(20 "In9.Cu" signal "VCC1")
		(22 "In10.Cu" signal "GND4")
		(24 "In11.Cu" signal "IN4")
		(26 "In12.Cu" signal "GND5")
		(28 "In13.Cu" signal "IN5")
		(30 "In14.Cu" signal "GND6")
		(32 "In15.Cu" signal "IN6")
		(34 "In16.Cu" signal "GND7")
		(2 "B.Cu" signal "BOTTOM")
		(9 "F.Adhes" user "F.Adhesive")
		(11 "B.Adhes" user "B.Adhesive")
		(13 "F.Paste" user "Package Geometry/Pastemask Top")
		(15 "B.Paste" user "Package Geometry/Pastemask Bottom")
		(5 "F.SilkS" user "Ref Des/Silkscreen Top")
		(7 "B.SilkS" user "Ref Des/Silkscreen Bottom")
		(1 "F.Mask" user "Board Geometry/Soldermask Top")
		(3 "B.Mask" user "Board Geometry/Soldermask Bottom")
		(17 "Dwgs.User" user "User.Drawings")
		(19 "Cmts.User" user "User.Comments")
		(21 "Eco1.User" user "User.Eco1")
		(23 "Eco2.User" user "User.Eco2")
		(25 "Edge.Cuts" user "Board Geometry/Outline")
		(27 "Margin" user)
		(31 "F.CrtYd" user "Package Geometry/Place Bound Top")
		(29 "B.CrtYd" user "Package Geometry/Place Bound Bottom")
		(35 "F.Fab" user "Ref Des/Assembly Top")
		(33 "B.Fab" user "Ref Des/Assembly Bottom")
	)
	(footprint ""
		(layer "F.Cu")
		(at 486.113836 -470.036144)
		(property "Reference" "JP4003_12"
			(at -2.172716 -3.824224 0)
			(unlocked yes)
			(layer "F.SilkS")
			(effects
				(font
					(size 0.7874 0.5842)
					(thickness 0.1524)
				)
				(justify left)
			)
		)
		(property "Value" ""
			(at 0 0 0)
			(layer "F.Fab")
			(effects
				(font
					(size 1.27 1.27)
				)
			)
		)
		(duplicate_pad_numbers_are_jumpers no)
		(pad "1" smd circle
			(at 0 0)
			(size 0.762 0.762)
			(layers "F.Cu" "F.Mask" "F.Paste")
			(net "Net_8607")
		)
	)
	(footprint ""
		(layer "F.Cu")
		(at 371.23624 -315.66739 90)
		(property "Reference" "PC16"
			(at 0 0 90)
			(layer "F.SilkS")
			(hide yes)
			(effects
				(font
					(size 1.27 1.27)
				)
			)
		)
		(property "Value" ""
			(at 0 0 90)
			(layer "F.Fab")
			(effects
				(font
					(size 1.27 1.27)
				)
			)
		)
		(duplicate_pad_numbers_are_jumpers no)
		(fp_line
			(start 2.750058 0.999998)
			(end -2.750058 0.999998)
			(stroke
				(width 0.1524)
				(type default)
			)
			(layer "F.SilkS")
		)
		(fp_circle
			(center 0 0.999998)
			(end 0 3.750056)
			(stroke
				(width 0.1524)
				(type default)
			)
			(fill no)
			(layer "F.SilkS")
		)
		(fp_poly
			(pts
				(arc
					(start 2.750058 0.999998)
					(mid 0 3.750056)
					(end -2.750058 0.999998)
				)
			)
			(stroke
				(width 0)
				(type default)
			)
			(fill yes)
			(layer "F.SilkS")
		)
		(fp_circle
			(center 0 0.999998)
			(end 0 3.750056)
			(stroke
				(width 0.1)
				(type default)
			)
			(fill no)
			(layer "F.Fab")
		)
		(pad "1" thru_hole rect
			(at 0 0 90)
			(size 1.5748 1.5748)
			(drill 1.0668)
			(layers "*.Cu" "*.Mask")
			(remove_unused_layers no)
			(net "PVCCIN_CPU0")
			(clearance 0)
			(padstack
				(mode front_inner_back)
				(layer "Inner"
					(shape circle)
					(size 1.5748 1.5748)
					(clearance 0)
				)
				(layer "B.Cu"
					(shape rect)
					(size 1.5748 1.5748)
					(clearance 0)
				)
			)
		)
		(pad "2" thru_hole circle
			(at 0 1.999996 90)
			(size 1.5748 1.5748)
			(drill 1.0668)
			(layers "*.Cu" "*.Mask")
			(remove_unused_layers no)
			(net "GND")
			(clearance 0)
		)
	)
	(footprint ""
		(layer "F.Cu")
		(at 131.466844 -132.707126 180)
		(property "Reference" "R3396"
			(at 0 0 180)
			(layer "F.SilkS")
			(hide yes)
			(effects
				(font
					(size 1.27 1.27)
				)
			)
		)
		(property "Value" ""
			(at 0 0 180)
			(layer "F.Fab")
			(effects
				(font
					(size 1.27 1.27)
				)
			)
		)
		(duplicate_pad_numbers_are_jumpers no)
		(fp_line
			(start 0.7874 0.4064)
			(end -0.7874 0.4064)
			(stroke
				(width 0.1524)
				(type default)
			)
			(layer "F.SilkS")
		)
		(fp_line
			(start 0.7874 -0.4064)
			(end 0.7874 0.4064)
			(stroke
				(width 0.1524)
				(type default)
			)
			(layer "F.SilkS")
		)
		(fp_line
			(start -0.7874 0.4064)
			(end -0.7874 -0.4064)
			(stroke
				(width 0.1524)
				(type default)
			)
			(layer "F.SilkS")
		)
		(fp_line
			(start -0.7874 -0.4064)
			(end 0.7874 -0.4064)
			(stroke
				(width 0.1524)
				(type default)
			)
			(layer "F.SilkS")
		)
		(fp_line
			(start 0.67945 0.3048)
			(end 0.120396 0.3048)
			(stroke
				(width 0.1)
				(type default)
			)
			(layer "F.Fab")
		)
		(fp_line
			(start 0.67945 -0.3048)
			(end 0.67945 0.3048)
			(stroke
				(width 0.1)
				(type default)
			)
			(layer "F.Fab")
		)
		(fp_line
			(start 0.12065 -0.2794)
			(end 0.12065 -0.3048)
			(stroke
				(width 0.1)
				(type default)
			)
			(layer "F.Fab")
		)
		(fp_line
			(start 0.12065 -0.3048)
			(end 0.67945 -0.3048)
			(stroke
				(width 0.1)
				(type default)
			)
			(layer "F.Fab")
		)
		(fp_line
			(start 0.120396 0.3048)
			(end 0.120396 0.2794)
			(stroke
				(width 0.1)
				(type default)
			)
			(layer "F.Fab")
		)
		(fp_line
			(start 0.120396 0.2794)
			(end -0.12065 0.2794)
			(stroke
				(width 0.1)
				(type default)
			)
			(layer "F.Fab")
		)
		(fp_line
			(start -0.12065 0.3048)
			(end -0.67945 0.3048)
			(stroke
				(width 0.1)
				(type default)
			)
			(layer "F.Fab")
		)
		(fp_line
			(start -0.12065 0.2794)
			(end -0.12065 0.3048)
			(stroke
				(width 0.1)
				(type default)
			)
			(layer "F.Fab")
		)
		(fp_line
			(start -0.12065 -0.2794)
			(end 0.12065 -0.2794)
			(stroke
				(width 0.1)
				(type default)
			)
			(layer "F.Fab")
		)
		(fp_line
			(start -0.12065 -0.305054)
			(end -0.12065 -0.2794)
			(stroke
				(width 0.1)
				(type default)
			)
			(layer "F.Fab")
		)
		(fp_line
			(start -0.67945 0.3048)
			(end -0.67945 -0.305054)
			(stroke
				(width 0.1)
				(type default)
			)
			(layer "F.Fab")
		)
		(fp_line
			(start -0.67945 -0.305054)
			(end -0.12065 -0.305054)
			(stroke
				(width 0.1)
				(type default)
			)
			(layer "F.Fab")
		)
		(pad "1" smd circle
			(at -0.40005 0 180)
			(size 0 0)
			(layers "F.Cu" "F.Mask" "F.Paste")
			(net "P3V3_AUX")
		)
		(pad "2" smd circle
			(at 0.40005 0 180)
			(size 0 0)
			(layers "F.Cu" "F.Mask" "F.Paste")
			(net "SMB_INA230_3V3AUX_SDA")
		)
	)
	(footprint ""
		(layer "F.Cu")
		(at 144.564608 -106.168698 -90)
		(property "Reference" "R4391"
			(at 0 0 270)
			(layer "F.SilkS")
			(hide yes)
			(effects
				(font
					(size 1.27 1.27)
				)
			)
		)
		(property "Value" ""
			(at 0 0 270)
			(layer "F.Fab")
			(effects
				(font
					(size 1.27 1.27)
				)
			)
		)
		(duplicate_pad_numbers_are_jumpers no)
		(fp_line
			(start -0.7874 0.4064)
			(end -0.7874 -0.4064)
			(stroke
				(width 0.1524)
				(type default)
			)
			(layer "F.SilkS")
		)
		(fp_line
			(start 0.7874 0.4064)
			(end -0.7874 0.4064)
			(stroke
				(width 0.1524)
				(type default)
			)
			(layer "F.SilkS")
		)
		(fp_line
			(start -0.7874 -0.4064)
			(end 0.7874 -0.4064)
			(stroke
				(width 0.1524)
				(type default)
			)
			(layer "F.SilkS")
		)
		(fp_line
			(start 0.7874 -0.4064)
			(end 0.7874 0.4064)
			(stroke
				(width 0.1524)
				(type default)
			)
			(layer "F.SilkS")
		)
		(fp_line
			(start -0.67945 0.3048)
			(end -0.67945 -0.305054)
			(stroke
				(width 0.1)
				(type default)
			)
			(layer "F.Fab")
		)
		(fp_line
			(start -0.12065 0.3048)
			(end -0.67945 0.3048)
			(stroke
				(width 0.1)
				(type default)
			)
			(layer "F.Fab")
		)
		(fp_line
			(start 0.120396 0.3048)
			(end 0.120396 0.2794)
			(stroke
				(width 0.1)
				(type default)
			)
			(layer "F.Fab")
		)
		(fp_line
			(start 0.67945 0.3048)
			(end 0.120396 0.3048)
			(stroke
				(width 0.1)
				(type default)
			)
			(layer "F.Fab")
		)
		(fp_line
			(start -0.12065 0.2794)
			(end -0.12065 0.3048)
			(stroke
				(width 0.1)
				(type default)
			)
			(layer "F.Fab")
		)
		(fp_line
			(start 0.120396 0.2794)
			(end -0.12065 0.2794)
			(stroke
				(width 0.1)
				(type default)
			)
			(layer "F.Fab")
		)
		(fp_line
			(start -0.12065 -0.2794)
			(end 0.12065 -0.2794)
			(stroke
				(width 0.1)
				(type default)
			)
			(layer "F.Fab")
		)
		(fp_line
			(start 0.12065 -0.2794)
			(end 0.12065 -0.3048)
			(stroke
				(width 0.1)
				(type default)
			)
			(layer "F.Fab")
		)
		(fp_line
			(start 0.12065 -0.3048)
			(end 0.67945 -0.3048)
			(stroke
				(width 0.1)
				(type default)
			)
			(layer "F.Fab")
		)
		(fp_line
			(start 0.67945 -0.3048)
			(end 0.67945 0.3048)
			(stroke
				(width 0.1)
				(type default)
			)
			(layer "F.Fab")
		)
		(fp_line
			(start -0.67945 -0.305054)
			(end -0.12065 -0.305054)
			(stroke
				(width 0.1)
				(type default)
			)
			(layer "F.Fab")
		)
		(fp_line
			(start -0.12065 -0.305054)
			(end -0.12065 -0.2794)
			(stroke
				(width 0.1)
				(type default)
			)
			(layer "F.Fab")
		)
		(pad "1" smd circle
			(at -0.40005 0 270)
			(size 0 0)
			(layers "F.Cu" "F.Mask" "F.Paste")
			(net "PD_GTL2014_ERROR_B0")
		)
		(pad "2" smd circle
			(at 0.40005 0 270)
			(size 0 0)
			(layers "F.Cu" "F.Mask" "F.Paste")
			(net "GND")
		)
	)
)
